# S9S_MB_2U (Grand Teton) — schematic netlist excerpt (pin names and nets, part order shuffled) for the footprints in the layout excerpt that follows; sources: Cadence DE-HDL packaged netlist, KiCad conversion of 03242023_DA0F0TMBIJ0_F0T_Motherboard_J_brd_V01_OCP.brd

C692  Q_CAP_DIFFBUS  DIFF BUS_0.22UF 6.3V 20% X6S  pkg C0201  page 177 : \1\ = P5E_CPU1_PE4_TX_C_DN<8> ; \2\ = P5E_CPU1_PE4_TX_DN<8>
R3864  Q_RES  0 5% EMPTY  pkg 0402LF  page 250 : A = P12V_OCP_SFF_ISENSE_MPS_MAM ; B = P12V_OCP_SFF_ISENSE_MAM

(kicad_pcb
	(version 20260206)
	(generator "pcbnew")
	(generator_version "10.0")
	(general
		(thickness 1.6)
		(legacy_teardrops no)
	)
	(paper "A4")
	(title_block
		(title "03242023_DA0F0TMBIJ0_F0T_Motherboard_J_brd_V01_OCP.brd")
		(comment 1 "Grand Teton / footprints 1202-1203 of 6105")
	)
	(layers
		(0 "F.Cu" signal "TOP")
		(4 "In1.Cu" signal "GND")
		(6 "In2.Cu" signal "IN1")
		(8 "In3.Cu" signal "GND1")
		(10 "In4.Cu" signal "IN2")
		(12 "In5.Cu" signal "GND2")
		(14 "In6.Cu" signal "IN3")
		(16 "In7.Cu" signal "GND3")
		(18 "In8.Cu" signal "VCC")
		(20 "In9.Cu" signal "VCC1")
		(22 "In10.Cu" signal "GND4")
		(24 "In11.Cu" signal "IN4")
		(26 "In12.Cu" signal "GND5")
		(28 "In13.Cu" signal "IN5")
		(30 "In14.Cu" signal "GND6")
		(32 "In15.Cu" signal "IN6")
		(34 "In16.Cu" signal "GND7")
		(2 "B.Cu" signal "BOTTOM")
		(9 "F.Adhes" user "F.Adhesive")
		(11 "B.Adhes" user "B.Adhesive")
		(13 "F.Paste" user "Package Geometry/Pastemask Top")
		(15 "B.Paste" user "Package Geometry/Pastemask Bottom")
		(5 "F.SilkS" user "Ref Des/Silkscreen Top")
		(7 "B.SilkS" user "Ref Des/Silkscreen Bottom")
		(1 "F.Mask" user "Board Geometry/Soldermask Top")
		(3 "B.Mask" user "Board Geometry/Soldermask Bottom")
		(17 "Dwgs.User" user "User.Drawings")
		(19 "Cmts.User" user "User.Comments")
		(21 "Eco1.User" user "User.Eco1")
		(23 "Eco2.User" user "User.Eco2")
		(25 "Edge.Cuts" user "Board Geometry/Outline")
		(27 "Margin" user)
		(31 "F.CrtYd" user "Package Geometry/Place Bound Top")
		(29 "B.CrtYd" user "Package Geometry/Place Bound Bottom")
		(35 "F.Fab" user "Ref Des/Assembly Top")
		(33 "B.Fab" user "Ref Des/Assembly Bottom")
	)
	(footprint ""
		(layer "F.Cu")
		(at 29.332428 -99.586034 180)
		(property "Reference" "R3864"
			(at 0 0 180)
			(layer "F.SilkS")
			(hide yes)
			(effects
				(font
					(size 1.27 1.27)
				)
			)
		)
		(property "Value" ""
			(at 0 0 180)
			(layer "F.Fab")
			(effects
				(font
					(size 1.27 1.27)
				)
			)
		)
		(duplicate_pad_numbers_are_jumpers no)
		(fp_line
			(start 0.7874 0.4064)
			(end -0.7874 0.4064)
			(stroke
				(width 0.1524)
				(type default)
			)
			(layer "F.SilkS")
		)
		(fp_line
			(start 0.7874 -0.4064)
			(end 0.7874 0.4064)
			(stroke
				(width 0.1524)
				(type default)
			)
			(layer "F.SilkS")
		)
		(fp_line
			(start -0.7874 0.4064)
			(end -0.7874 -0.4064)
			(stroke
				(width 0.1524)
				(type default)
			)
			(layer "F.SilkS")
		)
		(fp_line
			(start -0.7874 -0.4064)
			(end 0.7874 -0.4064)
			(stroke
				(width 0.1524)
				(type default)
			)
			(layer "F.SilkS")
		)
		(fp_line
			(start 0.67945 0.3048)
			(end 0.120396 0.3048)
			(stroke
				(width 0.1)
				(type default)
			)
			(layer "F.Fab")
		)
		(fp_line
			(start 0.67945 -0.3048)
			(end 0.67945 0.3048)
			(stroke
				(width 0.1)
				(type default)
			)
			(layer "F.Fab")
		)
		(fp_line
			(start 0.12065 -0.2794)
			(end 0.12065 -0.3048)
			(stroke
				(width 0.1)
				(type default)
			)
			(layer "F.Fab")
		)
		(fp_line
			(start 0.12065 -0.3048)
			(end 0.67945 -0.3048)
			(stroke
				(width 0.1)
				(type default)
			)
			(layer "F.Fab")
		)
		(fp_line
			(start 0.120396 0.3048)
			(end 0.120396 0.2794)
			(stroke
				(width 0.1)
				(type default)
			)
			(layer "F.Fab")
		)
		(fp_line
			(start 0.120396 0.2794)
			(end -0.12065 0.2794)
			(stroke
				(width 0.1)
				(type default)
			)
			(layer "F.Fab")
		)
		(fp_line
			(start -0.12065 0.3048)
			(end -0.67945 0.3048)
			(stroke
				(width 0.1)
				(type default)
			)
			(layer "F.Fab")
		)
		(fp_line
			(start -0.12065 0.2794)
			(end -0.12065 0.3048)
			(stroke
				(width 0.1)
				(type default)
			)
			(layer "F.Fab")
		)
		(fp_line
			(start -0.12065 -0.2794)
			(end 0.12065 -0.2794)
			(stroke
				(width 0.1)
				(type default)
			)
			(layer "F.Fab")
		)
		(fp_line
			(start -0.12065 -0.305054)
			(end -0.12065 -0.2794)
			(stroke
				(width 0.1)
				(type default)
			)
			(layer "F.Fab")
		)
		(fp_line
			(start -0.67945 0.3048)
			(end -0.67945 -0.305054)
			(stroke
				(width 0.1)
				(type default)
			)
			(layer "F.Fab")
		)
		(fp_line
			(start -0.67945 -0.305054)
			(end -0.12065 -0.305054)
			(stroke
				(width 0.1)
				(type default)
			)
			(layer "F.Fab")
		)
		(pad "1" smd rect
			(at -0.40005 0)
			(size 0.4572 0.508)
			(layers "F.Cu" "F.Mask" "F.Paste")
			(net "P12V_OCP_SFF_ISENSE_MPS_MAM")
		)
		(pad "2" smd rect
			(at 0.40005 0)
			(size 0.4572 0.508)
			(layers "F.Cu" "F.Mask" "F.Paste")
			(net "P12V_OCP_SFF_ISENSE_MAM")
		)
	)
	(footprint ""
		(layer "F.Cu")
		(at 73.806558 -408.517344 -90)
		(property "Reference" "C692"
			(at 0 0 270)
			(layer "F.SilkS")
			(hide yes)
			(effects
				(font
					(size 1.27 1.27)
				)
			)
		)
		(property "Value" ""
			(at 0 0 270)
			(layer "F.Fab")
			(effects
				(font
					(size 1.27 1.27)
				)
			)
		)
		(duplicate_pad_numbers_are_jumpers no)
		(fp_line
			(start -0.299974 0.150114)
			(end -0.299974 -0.150114)
			(stroke
				(width 0.1)
				(type default)
			)
			(layer "F.Fab")
		)
		(fp_line
			(start 0.299974 0.150114)
			(end -0.299974 0.150114)
			(stroke
				(width 0.1)
				(type default)
			)
			(layer "F.Fab")
		)
		(fp_line
			(start -0.299974 -0.150114)
			(end 0.299974 -0.150114)
			(stroke
				(width 0.1)
				(type default)
			)
			(layer "F.Fab")
		)
		(fp_line
			(start 0.299974 -0.150114)
			(end 0.299974 0.150114)
			(stroke
				(width 0.1)
				(type default)
			)
			(layer "F.Fab")
		)
		(pad "1" smd rect
			(at -0.2667 0 270)
			(size 0.3048 0.381)
			(layers "F.Cu" "F.Mask" "F.Paste")
			(net "P5E_CPU1_PE4_TX_C_DN<8>")
		)
		(pad "2" smd rect
			(at 0.2667 0 270)
			(size 0.3048 0.381)
			(layers "F.Cu" "F.Mask" "F.Paste")
			(net "P5E_CPU1_PE4_TX_DN<8>")
		)
	)
)
